# T6G (Grand Teton) — schematic netlist excerpt (pin names and nets, part order shuffled) for the footprints in the layout excerpt that follows; sources: Cadence DE-HDL packaged netlist, KiCad conversion of 04192023_DAF0TMB3IC0_F0TG_MB_C_brd_V02_OCP.brd

R1643  Q_RES  22 1% CHIP  pkg 0402LF  page 173 : A = JTAG_P1_R_TMS ; B = JTAG_CPU1_TMS
PC96  Q_CAP  0.1UF 25V 10% X7R  pkg 0402  page 224 : A = PVDD11_S3_P1_VCCS ; B = GND
R636  Q_RES  51.1 1% EMPTY  pkg 0201LF  page 309 : A = CLK_100M_RETIMER_CPU0_P3_DP ; B = GND

(kicad_pcb
	(version 20260206)
	(generator "pcbnew")
	(generator_version "10.0")
	(general
		(thickness 1.6)
		(legacy_teardrops no)
	)
	(paper "A4")
	(title_block
		(title "04192023_DAF0TMB3IC0_F0TG_MB_C_brd_V02_OCP.brd")
		(comment 1 "Grand Teton / footprints 512-514 of 8354")
	)
	(layers
		(0 "F.Cu" signal "TOP")
		(4 "In1.Cu" signal "GND")
		(6 "In2.Cu" signal "IN1")
		(8 "In3.Cu" signal "GND1")
		(10 "In4.Cu" signal "IN2")
		(12 "In5.Cu" signal "GND2")
		(14 "In6.Cu" signal "IN3")
		(16 "In7.Cu" signal "GND3")
		(18 "In8.Cu" signal "VCC")
		(20 "In9.Cu" signal "VCC1")
		(22 "In10.Cu" signal "GND4")
		(24 "In11.Cu" signal "IN4")
		(26 "In12.Cu" signal "GND5")
		(28 "In13.Cu" signal "IN5")
		(30 "In14.Cu" signal "GND6")
		(32 "In15.Cu" signal "IN6")
		(34 "In16.Cu" signal "GND7")
		(2 "B.Cu" signal "BOTTOM")
		(9 "F.Adhes" user "F.Adhesive")
		(11 "B.Adhes" user "B.Adhesive")
		(13 "F.Paste" user "Package Geometry/Pastemask Top")
		(15 "B.Paste" user "Package Geometry/Pastemask Bottom")
		(5 "F.SilkS" user "Ref Des/Silkscreen Top")
		(7 "B.SilkS" user "Ref Des/Silkscreen Bottom")
		(1 "F.Mask" user "Board Geometry/Soldermask Top")
		(3 "B.Mask" user "Board Geometry/Soldermask Bottom")
		(17 "Dwgs.User" user "User.Drawings")
		(19 "Cmts.User" user "User.Comments")
		(21 "Eco1.User" user "User.Eco1")
		(23 "Eco2.User" user "User.Eco2")
		(25 "Edge.Cuts" user "Board Geometry/Outline")
		(27 "Margin" user)
		(31 "F.CrtYd" user "Package Geometry/Place Bound Top")
		(29 "B.CrtYd" user "Package Geometry/Place Bound Bottom")
		(35 "F.Fab" user "Ref Des/Assembly Top")
		(33 "B.Fab" user "Ref Des/Assembly Bottom")
	)
	(footprint ""
		(layer "F.Cu")
		(at 163.465002 -352.652838 90)
		(property "Reference" "PC96"
			(at 0 0 90)
			(layer "F.SilkS")
			(hide yes)
			(effects
				(font
					(size 1.27 1.27)
				)
			)
		)
		(property "Value" ""
			(at 0 0 90)
			(layer "F.Fab")
			(effects
				(font
					(size 1.27 1.27)
				)
			)
		)
		(duplicate_pad_numbers_are_jumpers no)
		(fp_line
			(start 0.7874 -0.4064)
			(end 0.7874 0.4064)
			(stroke
				(width 0.1524)
				(type default)
			)
			(layer "F.SilkS")
		)
		(fp_line
			(start -0.7874 -0.4064)
			(end 0.7874 -0.4064)
			(stroke
				(width 0.1524)
				(type default)
			)
			(layer "F.SilkS")
		)
		(fp_line
			(start 0.7874 0.4064)
			(end -0.7874 0.4064)
			(stroke
				(width 0.1524)
				(type default)
			)
			(layer "F.SilkS")
		)
		(fp_line
			(start -0.7874 0.4064)
			(end -0.7874 -0.4064)
			(stroke
				(width 0.1524)
				(type default)
			)
			(layer "F.SilkS")
		)
		(fp_line
			(start -0.12065 -0.305054)
			(end -0.12065 -0.2794)
			(stroke
				(width 0.1)
				(type default)
			)
			(layer "F.Fab")
		)
		(fp_line
			(start -0.67945 -0.305054)
			(end -0.12065 -0.305054)
			(stroke
				(width 0.1)
				(type default)
			)
			(layer "F.Fab")
		)
		(fp_line
			(start 0.67945 -0.3048)
			(end 0.67945 0.3048)
			(stroke
				(width 0.1)
				(type default)
			)
			(layer "F.Fab")
		)
		(fp_line
			(start 0.12065 -0.3048)
			(end 0.67945 -0.3048)
			(stroke
				(width 0.1)
				(type default)
			)
			(layer "F.Fab")
		)
		(fp_line
			(start 0.12065 -0.2794)
			(end 0.12065 -0.3048)
			(stroke
				(width 0.1)
				(type default)
			)
			(layer "F.Fab")
		)
		(fp_line
			(start -0.12065 -0.2794)
			(end 0.12065 -0.2794)
			(stroke
				(width 0.1)
				(type default)
			)
			(layer "F.Fab")
		)
		(fp_line
			(start 0.120396 0.2794)
			(end -0.12065 0.2794)
			(stroke
				(width 0.1)
				(type default)
			)
			(layer "F.Fab")
		)
		(fp_line
			(start -0.12065 0.2794)
			(end -0.12065 0.3048)
			(stroke
				(width 0.1)
				(type default)
			)
			(layer "F.Fab")
		)
		(fp_line
			(start 0.67945 0.3048)
			(end 0.120396 0.3048)
			(stroke
				(width 0.1)
				(type default)
			)
			(layer "F.Fab")
		)
		(fp_line
			(start 0.120396 0.3048)
			(end 0.120396 0.2794)
			(stroke
				(width 0.1)
				(type default)
			)
			(layer "F.Fab")
		)
		(fp_line
			(start -0.12065 0.3048)
			(end -0.67945 0.3048)
			(stroke
				(width 0.1)
				(type default)
			)
			(layer "F.Fab")
		)
		(fp_line
			(start -0.67945 0.3048)
			(end -0.67945 -0.305054)
			(stroke
				(width 0.1)
				(type default)
			)
			(layer "F.Fab")
		)
		(pad "1" smd circle
			(at -0.40005 0 90)
			(size 0 0)
			(layers "F.Cu" "F.Mask" "F.Paste")
			(net "PVDD11_S3_P1_VCCS")
		)
		(pad "2" smd circle
			(at 0.40005 0 90)
			(size 0 0)
			(layers "F.Cu" "F.Mask" "F.Paste")
			(net "GND")
		)
	)
	(footprint ""
		(layer "F.Cu")
		(at 275.14169 -97.339404 180)
		(property "Reference" "R1643"
			(at 0 0 180)
			(layer "F.SilkS")
			(hide yes)
			(effects
				(font
					(size 1.27 1.27)
				)
			)
		)
		(property "Value" ""
			(at 0 0 180)
			(layer "F.Fab")
			(effects
				(font
					(size 1.27 1.27)
				)
			)
		)
		(duplicate_pad_numbers_are_jumpers no)
		(fp_line
			(start 0.7874 0.4064)
			(end -0.7874 0.4064)
			(stroke
				(width 0.1524)
				(type default)
			)
			(layer "F.SilkS")
		)
		(fp_line
			(start 0.7874 -0.4064)
			(end 0.7874 0.4064)
			(stroke
				(width 0.1524)
				(type default)
			)
			(layer "F.SilkS")
		)
		(fp_line
			(start -0.7874 0.4064)
			(end -0.7874 -0.4064)
			(stroke
				(width 0.1524)
				(type default)
			)
			(layer "F.SilkS")
		)
		(fp_line
			(start -0.7874 -0.4064)
			(end 0.7874 -0.4064)
			(stroke
				(width 0.1524)
				(type default)
			)
			(layer "F.SilkS")
		)
		(fp_line
			(start 0.67945 0.3048)
			(end 0.120396 0.3048)
			(stroke
				(width 0.1)
				(type default)
			)
			(layer "F.Fab")
		)
		(fp_line
			(start 0.67945 -0.3048)
			(end 0.67945 0.3048)
			(stroke
				(width 0.1)
				(type default)
			)
			(layer "F.Fab")
		)
		(fp_line
			(start 0.12065 -0.2794)
			(end 0.12065 -0.3048)
			(stroke
				(width 0.1)
				(type default)
			)
			(layer "F.Fab")
		)
		(fp_line
			(start 0.12065 -0.3048)
			(end 0.67945 -0.3048)
			(stroke
				(width 0.1)
				(type default)
			)
			(layer "F.Fab")
		)
		(fp_line
			(start 0.120396 0.3048)
			(end 0.120396 0.2794)
			(stroke
				(width 0.1)
				(type default)
			)
			(layer "F.Fab")
		)
		(fp_line
			(start 0.120396 0.2794)
			(end -0.12065 0.2794)
			(stroke
				(width 0.1)
				(type default)
			)
			(layer "F.Fab")
		)
		(fp_line
			(start -0.12065 0.3048)
			(end -0.67945 0.3048)
			(stroke
				(width 0.1)
				(type default)
			)
			(layer "F.Fab")
		)
		(fp_line
			(start -0.12065 0.2794)
			(end -0.12065 0.3048)
			(stroke
				(width 0.1)
				(type default)
			)
			(layer "F.Fab")
		)
		(fp_line
			(start -0.12065 -0.2794)
			(end 0.12065 -0.2794)
			(stroke
				(width 0.1)
				(type default)
			)
			(layer "F.Fab")
		)
		(fp_line
			(start -0.12065 -0.305054)
			(end -0.12065 -0.2794)
			(stroke
				(width 0.1)
				(type default)
			)
			(layer "F.Fab")
		)
		(fp_line
			(start -0.67945 0.3048)
			(end -0.67945 -0.305054)
			(stroke
				(width 0.1)
				(type default)
			)
			(layer "F.Fab")
		)
		(fp_line
			(start -0.67945 -0.305054)
			(end -0.12065 -0.305054)
			(stroke
				(width 0.1)
				(type default)
			)
			(layer "F.Fab")
		)
		(pad "1" smd circle
			(at -0.40005 0 180)
			(size 0 0)
			(layers "F.Cu" "F.Mask" "F.Paste")
			(net "JTAG_P1_R_TMS")
		)
		(pad "2" smd circle
			(at 0.40005 0 180)
			(size 0 0)
			(layers "F.Cu" "F.Mask" "F.Paste")
			(net "JTAG_CPU1_TMS")
		)
	)
	(footprint ""
		(layer "F.Cu")
		(at 366.64392 -396.412974 90)
		(property "Reference" "R636"
			(at 0 0 90)
			(layer "F.SilkS")
			(hide yes)
			(effects
				(font
					(size 1.27 1.27)
				)
			)
		)
		(property "Value" ""
			(at 0 0 90)
			(layer "F.Fab")
			(effects
				(font
					(size 1.27 1.27)
				)
			)
		)
		(duplicate_pad_numbers_are_jumpers no)
		(fp_line
			(start 0.32512 -0.175006)
			(end 0.32512 0.175006)
			(stroke
				(width 0.1)
				(type default)
			)
			(layer "F.Fab")
		)
		(fp_line
			(start -0.32512 -0.175006)
			(end 0.32512 -0.175006)
			(stroke
				(width 0.1)
				(type default)
			)
			(layer "F.Fab")
		)
		(fp_line
			(start 0.32512 0.175006)
			(end -0.32512 0.175006)
			(stroke
				(width 0.1)
				(type default)
			)
			(layer "F.Fab")
		)
		(fp_line
			(start -0.32512 0.175006)
			(end -0.32512 -0.175006)
			(stroke
				(width 0.1)
				(type default)
			)
			(layer "F.Fab")
		)
		(pad "1" smd rect
			(at -0.2667 0 90)
			(size 0.3048 0.381)
			(layers "F.Cu" "F.Mask" "F.Paste")
			(net "CLK_100M_RETIMER_CPU0_P3_DP")
		)
		(pad "2" smd rect
			(at 0.2667 0 270)
			(size 0.3048 0.381)
			(layers "F.Cu" "F.Mask" "F.Paste")
			(net "GND")
		)
	)
)
